(kicad_pcb
	(version 20260206)
	(generator "pcbnew")
	(generator_version "10.0")
	(general
		(thickness 1.6)
		(legacy_teardrops no)
	)
	(paper "A4")
	(title_block
		(title "03242023_DA0F0TMBIJ0_F0T_Motherboard_J_brd_V01_OCP.brd")
		(comment 1 "Grand Teton / footprints 1055-1060 of 6105")
	)
	(layers
		(0 "F.Cu" signal "TOP")
		(4 "In1.Cu" signal "GND")
		(6 "In2.Cu" signal "IN1")
		(8 "In3.Cu" signal "GND1")
		(10 "In4.Cu" signal "IN2")
		(12 "In5.Cu" signal "GND2")
		(14 "In6.Cu" signal "IN3")
		(16 "In7.Cu" signal "GND3")
		(18 "In8.Cu" signal "VCC")
		(20 "In9.Cu" signal "VCC1")
		(22 "In10.Cu" signal "GND4")
		(24 "In11.Cu" signal "IN4")
		(26 "In12.Cu" signal "GND5")
		(28 "In13.Cu" signal "IN5")
		(30 "In14.Cu" signal "GND6")
		(32 "In15.Cu" signal "IN6")
		(34 "In16.Cu" signal "GND7")
		(2 "B.Cu" signal "BOTTOM")
		(9 "F.Adhes" user "F.Adhesive")
		(11 "B.Adhes" user "B.Adhesive")
		(13 "F.Paste" user "Package Geometry/Pastemask Top")
		(15 "B.Paste" user "Package Geometry/Pastemask Bottom")
		(5 "F.SilkS" user "Ref Des/Silkscreen Top")
		(7 "B.SilkS" user "Ref Des/Silkscreen Bottom")
		(1 "F.Mask" user "Board Geometry/Soldermask Top")
		(3 "B.Mask" user "Board Geometry/Soldermask Bottom")
		(17 "Dwgs.User" user "User.Drawings")
		(19 "Cmts.User" user "User.Comments")
		(21 "Eco1.User" user "User.Eco1")
		(23 "Eco2.User" user "User.Eco2")
		(25 "Edge.Cuts" user "Board Geometry/Outline")
		(27 "Margin" user)
		(31 "F.CrtYd" user "Package Geometry/Place Bound Top")
		(29 "B.CrtYd" user "Package Geometry/Place Bound Bottom")
		(35 "F.Fab" user "Ref Des/Assembly Top")
		(33 "B.Fab" user "Ref Des/Assembly Bottom")
	)
	(footprint ""
		(layer "F.Cu")
		(at 54.112414 -171.129198)
		(property "Reference" "PR1728"
			(at 0 0 0)
			(layer "F.SilkS")
			(hide yes)
			(effects
				(font
					(size 1.27 1.27)
				)
			)
		)
		(property "Value" ""
			(at 0 0 0)
			(layer "F.Fab")
			(effects
				(font
					(size 1.27 1.27)
				)
			)
		)
		(duplicate_pad_numbers_are_jumpers no)
		(fp_line
			(start -0.7874 -0.4064)
			(end 0.7874 -0.4064)
			(stroke
				(width 0.1524)
				(type default)
			)
			(layer "F.SilkS")
		)
		(fp_line
			(start -0.7874 0.4064)
			(end -0.7874 -0.4064)
			(stroke
				(width 0.1524)
				(type default)
			)
			(layer "F.SilkS")
		)
		(fp_line
			(start 0.7874 -0.4064)
			(end 0.7874 0.4064)
			(stroke
				(width 0.1524)
				(type default)
			)
			(layer "F.SilkS")
		)
		(fp_line
			(start 0.7874 0.4064)
			(end -0.7874 0.4064)
			(stroke
				(width 0.1524)
				(type default)
			)
			(layer "F.SilkS")
		)
		(fp_line
			(start -0.67945 -0.305054)
			(end -0.12065 -0.305054)
			(stroke
				(width 0.1)
				(type default)
			)
			(layer "F.Fab")
		)
		(fp_line
			(start -0.67945 0.3048)
			(end -0.67945 -0.305054)
			(stroke
				(width 0.1)
				(type default)
			)
			(layer "F.Fab")
		)
		(fp_line
			(start -0.12065 -0.305054)
			(end -0.12065 -0.2794)
			(stroke
				(width 0.1)
				(type default)
			)
			(layer "F.Fab")
		)
		(fp_line
			(start -0.12065 -0.2794)
			(end 0.12065 -0.2794)
			(stroke
				(width 0.1)
				(type default)
			)
			(layer "F.Fab")
		)
		(fp_line
			(start -0.12065 0.2794)
			(end -0.12065 0.3048)
			(stroke
				(width 0.1)
				(type default)
			)
			(layer "F.Fab")
		)
		(fp_line
			(start -0.12065 0.3048)
			(end -0.67945 0.3048)
			(stroke
				(width 0.1)
				(type default)
			)
			(layer "F.Fab")
		)
		(fp_line
			(start 0.120396 0.2794)
			(end -0.12065 0.2794)
			(stroke
				(width 0.1)
				(type default)
			)
			(layer "F.Fab")
		)
		(fp_line
			(start 0.120396 0.3048)
			(end 0.120396 0.2794)
			(stroke
				(width 0.1)
				(type default)
			)
			(layer "F.Fab")
		)
		(fp_line
			(start 0.12065 -0.3048)
			(end 0.67945 -0.3048)
			(stroke
				(width 0.1)
				(type default)
			)
			(layer "F.Fab")
		)
		(fp_line
			(start 0.12065 -0.2794)
			(end 0.12065 -0.3048)
			(stroke
				(width 0.1)
				(type default)
			)
			(layer "F.Fab")
		)
		(fp_line
			(start 0.67945 -0.3048)
			(end 0.67945 0.3048)
			(stroke
				(width 0.1)
				(type default)
			)
			(layer "F.Fab")
		)
		(fp_line
			(start 0.67945 0.3048)
			(end 0.120396 0.3048)
			(stroke
				(width 0.1)
				(type default)
			)
			(layer "F.Fab")
		)
		(pad "1" smd circle
			(at -0.40005 0)
			(size 0 0)
			(layers "F.Cu" "F.Mask" "F.Paste")
			(net "PVCCFA_EHV_CPU1_LSET1")
		)
		(pad "2" smd circle
			(at 0.40005 0)
			(size 0 0)
			(layers "F.Cu" "F.Mask" "F.Paste")
			(net "GND")
		)
	)
	(footprint ""
		(layer "F.Cu")
		(at 164.67328 -21.783548 -90)
		(property "Reference" "R142"
			(at 0 0 270)
			(layer "F.SilkS")
			(hide yes)
			(effects
				(font
					(size 1.27 1.27)
				)
			)
		)
		(property "Value" ""
			(at 0 0 270)
			(layer "F.Fab")
			(effects
				(font
					(size 1.27 1.27)
				)
			)
		)
		(duplicate_pad_numbers_are_jumpers no)
		(fp_line
			(start -0.7874 0.4064)
			(end -0.7874 -0.4064)
			(stroke
				(width 0.1524)
				(type default)
			)
			(layer "F.SilkS")
		)
		(fp_line
			(start 0.7874 0.4064)
			(end -0.7874 0.4064)
			(stroke
				(width 0.1524)
				(type default)
			)
			(layer "F.SilkS")
		)
		(fp_line
			(start -0.7874 -0.4064)
			(end 0.7874 -0.4064)
			(stroke
				(width 0.1524)
				(type default)
			)
			(layer "F.SilkS")
		)
		(fp_line
			(start 0.7874 -0.4064)
			(end 0.7874 0.4064)
			(stroke
				(width 0.1524)
				(type default)
			)
			(layer "F.SilkS")
		)
		(fp_line
			(start -0.67945 0.3048)
			(end -0.67945 -0.305054)
			(stroke
				(width 0.1)
				(type default)
			)
			(layer "F.Fab")
		)
		(fp_line
			(start -0.12065 0.3048)
			(end -0.67945 0.3048)
			(stroke
				(width 0.1)
				(type default)
			)
			(layer "F.Fab")
		)
		(fp_line
			(start 0.120396 0.3048)
			(end 0.120396 0.2794)
			(stroke
				(width 0.1)
				(type default)
			)
			(layer "F.Fab")
		)
		(fp_line
			(start 0.67945 0.3048)
			(end 0.120396 0.3048)
			(stroke
				(width 0.1)
				(type default)
			)
			(layer "F.Fab")
		)
		(fp_line
			(start -0.12065 0.2794)
			(end -0.12065 0.3048)
			(stroke
				(width 0.1)
				(type default)
			)
			(layer "F.Fab")
		)
		(fp_line
			(start 0.120396 0.2794)
			(end -0.12065 0.2794)
			(stroke
				(width 0.1)
				(type default)
			)
			(layer "F.Fab")
		)
		(fp_line
			(start -0.12065 -0.2794)
			(end 0.12065 -0.2794)
			(stroke
				(width 0.1)
				(type default)
			)
			(layer "F.Fab")
		)
		(fp_line
			(start 0.12065 -0.2794)
			(end 0.12065 -0.3048)
			(stroke
				(width 0.1)
				(type default)
			)
			(layer "F.Fab")
		)
		(fp_line
			(start 0.12065 -0.3048)
			(end 0.67945 -0.3048)
			(stroke
				(width 0.1)
				(type default)
			)
			(layer "F.Fab")
		)
		(fp_line
			(start 0.67945 -0.3048)
			(end 0.67945 0.3048)
			(stroke
				(width 0.1)
				(type default)
			)
			(layer "F.Fab")
		)
		(fp_line
			(start -0.67945 -0.305054)
			(end -0.12065 -0.305054)
			(stroke
				(width 0.1)
				(type default)
			)
			(layer "F.Fab")
		)
		(fp_line
			(start -0.12065 -0.305054)
			(end -0.12065 -0.2794)
			(stroke
				(width 0.1)
				(type default)
			)
			(layer "F.Fab")
		)
		(pad "1" smd circle
			(at -0.40005 0 270)
			(size 0 0)
			(layers "F.Cu" "F.Mask" "F.Paste")
			(net "PVNN_TERM_CPU0")
		)
		(pad "2" smd circle
			(at 0.40005 0 270)
			(size 0 0)
			(layers "F.Cu" "F.Mask" "F.Paste")
			(net "PVCCIO_PECI_BMC")
		)
	)
	(footprint ""
		(layer "F.Cu")
		(at 36.930584 -105.425748)
		(property "Reference" "C2194"
			(at 0 0 0)
			(layer "F.SilkS")
			(hide yes)
			(effects
				(font
					(size 1.27 1.27)
				)
			)
		)
		(property "Value" ""
			(at 0 0 0)
			(layer "F.Fab")
			(effects
				(font
					(size 1.27 1.27)
				)
			)
		)
		(duplicate_pad_numbers_are_jumpers no)
		(fp_line
			(start -0.7874 -0.4064)
			(end 0.7874 -0.4064)
			(stroke
				(width 0.1524)
				(type default)
			)
			(layer "F.SilkS")
		)
		(fp_line
			(start -0.7874 0.4064)
			(end -0.7874 -0.4064)
			(stroke
				(width 0.1524)
				(type default)
			)
			(layer "F.SilkS")
		)
		(fp_line
			(start 0.7874 -0.4064)
			(end 0.7874 0.4064)
			(stroke
				(width 0.1524)
				(type default)
			)
			(layer "F.SilkS")
		)
		(fp_line
			(start 0.7874 0.4064)
			(end -0.7874 0.4064)
			(stroke
				(width 0.1524)
				(type default)
			)
			(layer "F.SilkS")
		)
		(fp_line
			(start -0.67945 -0.305054)
			(end -0.12065 -0.305054)
			(stroke
				(width 0.1)
				(type default)
			)
			(layer "F.Fab")
		)
		(fp_line
			(start -0.67945 0.3048)
			(end -0.67945 -0.305054)
			(stroke
				(width 0.1)
				(type default)
			)
			(layer "F.Fab")
		)
		(fp_line
			(start -0.12065 -0.305054)
			(end -0.12065 -0.2794)
			(stroke
				(width 0.1)
				(type default)
			)
			(layer "F.Fab")
		)
		(fp_line
			(start -0.12065 -0.2794)
			(end 0.12065 -0.2794)
			(stroke
				(width 0.1)
				(type default)
			)
			(layer "F.Fab")
		)
		(fp_line
			(start -0.12065 0.2794)
			(end -0.12065 0.3048)
			(stroke
				(width 0.1)
				(type default)
			)
			(layer "F.Fab")
		)
		(fp_line
			(start -0.12065 0.3048)
			(end -0.67945 0.3048)
			(stroke
				(width 0.1)
				(type default)
			)
			(layer "F.Fab")
		)
		(fp_line
			(start 0.120396 0.2794)
			(end -0.12065 0.2794)
			(stroke
				(width 0.1)
				(type default)
			)
			(layer "F.Fab")
		)
		(fp_line
			(start 0.120396 0.3048)
			(end 0.120396 0.2794)
			(stroke
				(width 0.1)
				(type default)
			)
			(layer "F.Fab")
		)
		(fp_line
			(start 0.12065 -0.3048)
			(end 0.67945 -0.3048)
			(stroke
				(width 0.1)
				(type default)
			)
			(layer "F.Fab")
		)
		(fp_line
			(start 0.12065 -0.2794)
			(end 0.12065 -0.3048)
			(stroke
				(width 0.1)
				(type default)
			)
			(layer "F.Fab")
		)
		(fp_line
			(start 0.67945 -0.3048)
			(end 0.67945 0.3048)
			(stroke
				(width 0.1)
				(type default)
			)
			(layer "F.Fab")
		)
		(fp_line
			(start 0.67945 0.3048)
			(end 0.120396 0.3048)
			(stroke
				(width 0.1)
				(type default)
			)
			(layer "F.Fab")
		)
		(pad "1" smd circle
			(at -0.40005 0)
			(size 0 0)
			(layers "F.Cu" "F.Mask" "F.Paste")
			(net "P12V_E1S_0_ISENSE_TIC")
		)
		(pad "2" smd circle
			(at 0.40005 0)
			(size 0 0)
			(layers "F.Cu" "F.Mask" "F.Paste")
			(net "GND")
		)
	)
	(footprint ""
		(layer "F.Cu")
		(at 406.124664 -366.437926 180)
		(property "Reference" "R650"
			(at 0 0 180)
			(layer "F.SilkS")
			(hide yes)
			(effects
				(font
					(size 1.27 1.27)
				)
			)
		)
		(property "Value" ""
			(at 0 0 180)
			(layer "F.Fab")
			(effects
				(font
					(size 1.27 1.27)
				)
			)
		)
		(duplicate_pad_numbers_are_jumpers no)
		(fp_line
			(start 0.7874 0.4064)
			(end -0.7874 0.4064)
			(stroke
				(width 0.1524)
				(type default)
			)
			(layer "F.SilkS")
		)
		(fp_line
			(start 0.7874 -0.4064)
			(end 0.7874 0.4064)
			(stroke
				(width 0.1524)
				(type default)
			)
			(layer "F.SilkS")
		)
		(fp_line
			(start -0.7874 0.4064)
			(end -0.7874 -0.4064)
			(stroke
				(width 0.1524)
				(type default)
			)
			(layer "F.SilkS")
		)
		(fp_line
			(start -0.7874 -0.4064)
			(end 0.7874 -0.4064)
			(stroke
				(width 0.1524)
				(type default)
			)
			(layer "F.SilkS")
		)
		(fp_line
			(start 0.67945 0.3048)
			(end 0.120396 0.3048)
			(stroke
				(width 0.1)
				(type default)
			)
			(layer "F.Fab")
		)
		(fp_line
			(start 0.67945 -0.3048)
			(end 0.67945 0.3048)
			(stroke
				(width 0.1)
				(type default)
			)
			(layer "F.Fab")
		)
		(fp_line
			(start 0.12065 -0.2794)
			(end 0.12065 -0.3048)
			(stroke
				(width 0.1)
				(type default)
			)
			(layer "F.Fab")
		)
		(fp_line
			(start 0.12065 -0.3048)
			(end 0.67945 -0.3048)
			(stroke
				(width 0.1)
				(type default)
			)
			(layer "F.Fab")
		)
		(fp_line
			(start 0.120396 0.3048)
			(end 0.120396 0.2794)
			(stroke
				(width 0.1)
				(type default)
			)
			(layer "F.Fab")
		)
		(fp_line
			(start 0.120396 0.2794)
			(end -0.12065 0.2794)
			(stroke
				(width 0.1)
				(type default)
			)
			(layer "F.Fab")
		)
		(fp_line
			(start -0.12065 0.3048)
			(end -0.67945 0.3048)
			(stroke
				(width 0.1)
				(type default)
			)
			(layer "F.Fab")
		)
		(fp_line
			(start -0.12065 0.2794)
			(end -0.12065 0.3048)
			(stroke
				(width 0.1)
				(type default)
			)
			(layer "F.Fab")
		)
		(fp_line
			(start -0.12065 -0.2794)
			(end 0.12065 -0.2794)
			(stroke
				(width 0.1)
				(type default)
			)
			(layer "F.Fab")
		)
		(fp_line
			(start -0.12065 -0.305054)
			(end -0.12065 -0.2794)
			(stroke
				(width 0.1)
				(type default)
			)
			(layer "F.Fab")
		)
		(fp_line
			(start -0.67945 0.3048)
			(end -0.67945 -0.305054)
			(stroke
				(width 0.1)
				(type default)
			)
			(layer "F.Fab")
		)
		(fp_line
			(start -0.67945 -0.305054)
			(end -0.12065 -0.305054)
			(stroke
				(width 0.1)
				(type default)
			)
			(layer "F.Fab")
		)
		(pad "1" smd circle
			(at -0.40005 0 180)
			(size 0 0)
			(layers "F.Cu" "F.Mask" "F.Paste")
			(net "P3V3_AUX")
		)
		(pad "2" smd circle
			(at 0.40005 0 180)
			(size 0 0)
			(layers "F.Cu" "F.Mask" "F.Paste")
			(net "PU_PIROM_CPU0_SM_WP")
		)
	)
	(footprint ""
		(layer "F.Cu")
		(at 68.085716 -114.74069 180)
		(property "Reference" "R3712"
			(at 0 0 180)
			(layer "F.SilkS")
			(hide yes)
			(effects
				(font
					(size 1.27 1.27)
				)
			)
		)
		(property "Value" ""
			(at 0 0 180)
			(layer "F.Fab")
			(effects
				(font
					(size 1.27 1.27)
				)
			)
		)
		(duplicate_pad_numbers_are_jumpers no)
		(fp_line
			(start 0.7874 0.4064)
			(end -0.7874 0.4064)
			(stroke
				(width 0.1524)
				(type default)
			)
			(layer "F.SilkS")
		)
		(fp_line
			(start 0.7874 -0.4064)
			(end 0.7874 0.4064)
			(stroke
				(width 0.1524)
				(type default)
			)
			(layer "F.SilkS")
		)
		(fp_line
			(start -0.7874 0.4064)
			(end -0.7874 -0.4064)
			(stroke
				(width 0.1524)
				(type default)
			)
			(layer "F.SilkS")
		)
		(fp_line
			(start -0.7874 -0.4064)
			(end 0.7874 -0.4064)
			(stroke
				(width 0.1524)
				(type default)
			)
			(layer "F.SilkS")
		)
		(fp_line
			(start 0.67945 0.3048)
			(end 0.120396 0.3048)
			(stroke
				(width 0.1)
				(type default)
			)
			(layer "F.Fab")
		)
		(fp_line
			(start 0.67945 -0.3048)
			(end 0.67945 0.3048)
			(stroke
				(width 0.1)
				(type default)
			)
			(layer "F.Fab")
		)
		(fp_line
			(start 0.12065 -0.2794)
			(end 0.12065 -0.3048)
			(stroke
				(width 0.1)
				(type default)
			)
			(layer "F.Fab")
		)
		(fp_line
			(start 0.12065 -0.3048)
			(end 0.67945 -0.3048)
			(stroke
				(width 0.1)
				(type default)
			)
			(layer "F.Fab")
		)
		(fp_line
			(start 0.120396 0.3048)
			(end 0.120396 0.2794)
			(stroke
				(width 0.1)
				(type default)
			)
			(layer "F.Fab")
		)
		(fp_line
			(start 0.120396 0.2794)
			(end -0.12065 0.2794)
			(stroke
				(width 0.1)
				(type default)
			)
			(layer "F.Fab")
		)
		(fp_line
			(start -0.12065 0.3048)
			(end -0.67945 0.3048)
			(stroke
				(width 0.1)
				(type default)
			)
			(layer "F.Fab")
		)
		(fp_line
			(start -0.12065 0.2794)
			(end -0.12065 0.3048)
			(stroke
				(width 0.1)
				(type default)
			)
			(layer "F.Fab")
		)
		(fp_line
			(start -0.12065 -0.2794)
			(end 0.12065 -0.2794)
			(stroke
				(width 0.1)
				(type default)
			)
			(layer "F.Fab")
		)
		(fp_line
			(start -0.12065 -0.305054)
			(end -0.12065 -0.2794)
			(stroke
				(width 0.1)
				(type default)
			)
			(layer "F.Fab")
		)
		(fp_line
			(start -0.67945 0.3048)
			(end -0.67945 -0.305054)
			(stroke
				(width 0.1)
				(type default)
			)
			(layer "F.Fab")
		)
		(fp_line
			(start -0.67945 -0.305054)
			(end -0.12065 -0.305054)
			(stroke
				(width 0.1)
				(type default)
			)
			(layer "F.Fab")
		)
		(pad "1" smd circle
			(at -0.40005 0 180)
			(size 0 0)
			(layers "F.Cu" "F.Mask" "F.Paste")
			(net "SMB_VR_SENSOR_3V3AUX_SDA")
		)
		(pad "2" smd circle
			(at 0.40005 0 180)
			(size 0 0)
			(layers "F.Cu" "F.Mask" "F.Paste")
			(net "SMB_VR_SENSOR_3V3AUX_SDA_R")
		)
	)
	(footprint ""
		(layer "F.Cu")
		(at 175.4124 -93.538548 90)
		(property "Reference" "R4582"
			(at 0 0 90)
			(layer "F.SilkS")
			(hide yes)
			(effects
				(font
					(size 1.27 1.27)
				)
			)
		)
		(property "Value" ""
			(at 0 0 90)
			(layer "F.Fab")
			(effects
				(font
					(size 1.27 1.27)
				)
			)
		)
		(duplicate_pad_numbers_are_jumpers no)
		(fp_line
			(start 0.7874 -0.4064)
			(end 0.7874 0.4064)
			(stroke
				(width 0.1524)
				(type default)
			)
			(layer "F.SilkS")
		)
		(fp_line
			(start -0.7874 -0.4064)
			(end 0.7874 -0.4064)
			(stroke
				(width 0.1524)
				(type default)
			)
			(layer "F.SilkS")
		)
		(fp_line
			(start 0.7874 0.4064)
			(end -0.7874 0.4064)
			(stroke
				(width 0.1524)
				(type default)
			)
			(layer "F.SilkS")
		)
		(fp_line
			(start -0.7874 0.4064)
			(end -0.7874 -0.4064)
			(stroke
				(width 0.1524)
				(type default)
			)
			(layer "F.SilkS")
		)
		(fp_line
			(start -0.12065 -0.305054)
			(end -0.12065 -0.2794)
			(stroke
				(width 0.1)
				(type default)
			)
			(layer "F.Fab")
		)
		(fp_line
			(start -0.67945 -0.305054)
			(end -0.12065 -0.305054)
			(stroke
				(width 0.1)
				(type default)
			)
			(layer "F.Fab")
		)
		(fp_line
			(start 0.67945 -0.3048)
			(end 0.67945 0.3048)
			(stroke
				(width 0.1)
				(type default)
			)
			(layer "F.Fab")
		)
		(fp_line
			(start 0.12065 -0.3048)
			(end 0.67945 -0.3048)
			(stroke
				(width 0.1)
				(type default)
			)
			(layer "F.Fab")
		)
		(fp_line
			(start 0.12065 -0.2794)
			(end 0.12065 -0.3048)
			(stroke
				(width 0.1)
				(type default)
			)
			(layer "F.Fab")
		)
		(fp_line
			(start -0.12065 -0.2794)
			(end 0.12065 -0.2794)
			(stroke
				(width 0.1)
				(type default)
			)
			(layer "F.Fab")
		)
		(fp_line
			(start 0.120396 0.2794)
			(end -0.12065 0.2794)
			(stroke
				(width 0.1)
				(type default)
			)
			(layer "F.Fab")
		)
		(fp_line
			(start -0.12065 0.2794)
			(end -0.12065 0.3048)
			(stroke
				(width 0.1)
				(type default)
			)
			(layer "F.Fab")
		)
		(fp_line
			(start 0.67945 0.3048)
			(end 0.120396 0.3048)
			(stroke
				(width 0.1)
				(type default)
			)
			(layer "F.Fab")
		)
		(fp_line
			(start 0.120396 0.3048)
			(end 0.120396 0.2794)
			(stroke
				(width 0.1)
				(type default)
			)
			(layer "F.Fab")
		)
		(fp_line
			(start -0.12065 0.3048)
			(end -0.67945 0.3048)
			(stroke
				(width 0.1)
				(type default)
			)
			(layer "F.Fab")
		)
		(fp_line
			(start -0.67945 0.3048)
			(end -0.67945 -0.305054)
			(stroke
				(width 0.1)
				(type default)
			)
			(layer "F.Fab")
		)
		(pad "1" smd rect
			(at -0.40005 0 270)
			(size 0.4572 0.508)
			(layers "F.Cu" "F.Mask" "F.Paste")
			(net "P3V3_AUX")
		)
		(pad "2" smd rect
			(at 0.40005 0 270)
			(size 0.4572 0.508)
			(layers "F.Cu" "F.Mask" "F.Paste")
			(net "FM_BOARD_BMC_SKU_ID1")
		)
	)
)
